(kicad_pcb
	(version 20260206)
	(generator "pcbnew")
	(generator_version "10.0")
	(general
		(thickness 1.6)
		(legacy_teardrops no)
	)
	(paper "A4")
	(title_block
		(title "netronome-mezz — pcbd0082-001_rev01_jul9_a.brd")
		(comment 1 "Open CloudServer (Microsoft) / footprint 225 of 714 (U1), pads 929-1022 of 1022")
	)
	(layers
		(0 "F.Cu" signal "TOP")
		(4 "In1.Cu" signal "02_GND")
		(6 "In2.Cu" signal "03_SIG")
		(8 "In3.Cu" signal "04_SIG")
		(10 "In4.Cu" signal "05_GND")
		(12 "In5.Cu" signal "06_PWR1")
		(14 "In6.Cu" signal "07_SIG")
		(16 "In7.Cu" signal "08_SIG")
		(18 "In8.Cu" signal "09_GND")
		(2 "B.Cu" signal "BOTTOM")
		(9 "F.Adhes" user "F.Adhesive")
		(11 "B.Adhes" user "B.Adhesive")
		(13 "F.Paste" user "Package Geometry/Pastemask Top")
		(15 "B.Paste" user "Package Geometry/Pastemask Bottom")
		(5 "F.SilkS" user "Ref Des/Silkscreen Top")
		(7 "B.SilkS" user "Ref Des/Silkscreen Bottom")
		(1 "F.Mask" user "Board Geometry/Soldermask Top")
		(3 "B.Mask" user "Board Geometry/Soldermask Bottom")
		(17 "Dwgs.User" user "User.Drawings")
		(19 "Cmts.User" user "User.Comments")
		(21 "Eco1.User" user "User.Eco1")
		(23 "Eco2.User" user "User.Eco2")
		(25 "Edge.Cuts" user "Board Geometry/Outline")
		(27 "Margin" user)
		(31 "F.CrtYd" user "Package Geometry/Place Bound Top")
		(29 "B.CrtYd" user "Package Geometry/Place Bound Bottom")
		(35 "F.Fab" user "Ref Des/Assembly Top")
		(33 "B.Fab" user "Ref Des/Assembly Bottom")
		(45 "User.4" user "COMPVAL_TYPE_BOTTOM")
	)
	(footprint ""
		(layer "F.Cu")
		(at 54.737 18.542 180)
		(property "Reference" "U1"
			(at -12.192 17.9705 0)
			(unlocked yes)
			(layer "F.SilkS")
			(effects
				(font
					(size 1.27 0.9652)
					(thickness 0.1524)
				)
				(justify left)
			)
		)
		(property "Value" "*"
			(at -0.4826 1.74879 180)
			(unlocked yes)
			(layer "F.Fab")
			(hide yes)
			(effects
				(font
					(size 1.27 0.9652)
					(thickness 0.000001)
				)
				(justify left)
			)
		)
		(property "Device Type" "ICBG0048"
			(at -0.4826 1.74879 180)
			(unlocked yes)
			(layer "F.Fab")
			(hide yes)
			(effects
				(font
					(size 1.27 0.9652)
					(thickness 0.000001)
				)
				(justify left)
			)
		)
		(duplicate_pad_numbers_are_jumpers no)
		(pad "V3" smd circle
			(at -13.499998 1.499997 180)
			(size 0.508 0.508)
			(layers "F.Cu" "F.Mask" "F.Paste")
			(net "GND")
		)
		(pad "V4" smd circle
			(at -12.5 1.499997 180)
			(size 0.508 0.508)
			(layers "F.Cu" "F.Mask" "F.Paste")
			(net "DDR0_32A_DQ28")
		)
		(pad "V5" smd circle
			(at -11.500002 1.499997 180)
			(size 0.508 0.508)
			(layers "F.Cu" "F.Mask" "F.Paste")
			(net "DDR0_32A_DM3")
		)
		(pad "V6" smd circle
			(at -10.500004 1.499997 180)
			(size 0.508 0.508)
			(layers "F.Cu" "F.Mask" "F.Paste")
			(net "GND")
		)
		(pad "V7" smd circle
			(at -9.500006 1.499997 180)
			(size 0.508 0.508)
			(layers "F.Cu" "F.Mask" "F.Paste")
			(net "DDR0_32A_CK0_N")
		)
		(pad "V8" smd circle
			(at -8.500008 1.499997 180)
			(size 0.508 0.508)
			(layers "F.Cu" "F.Mask" "F.Paste")
			(net "DDR0_32A_CK0_P")
		)
		(pad "V9" smd circle
			(at -7.50001 1.499997 180)
			(size 0.508 0.508)
			(layers "F.Cu" "F.Mask" "F.Paste")
			(net "_NC_DDR0_32A_CS1_L")
		)
		(pad "V10" smd circle
			(at -6.500012 1.499997 180)
			(size 0.508 0.508)
			(layers "F.Cu" "F.Mask" "F.Paste")
			(net "DDR0_32A_VREF")
		)
		(pad "V11" smd circle
			(at -5.499989 1.499997 180)
			(size 0.508 0.508)
			(layers "F.Cu" "F.Mask" "F.Paste")
			(net "GND")
		)
		(pad "V12" smd circle
			(at -4.499991 1.499997 180)
			(size 0.508 0.508)
			(layers "F.Cu" "F.Mask" "F.Paste")
			(net "VDD_CORE")
		)
		(pad "V13" smd circle
			(at -3.499993 1.499997 180)
			(size 0.508 0.508)
			(layers "F.Cu" "F.Mask" "F.Paste")
			(net "GND")
		)
		(pad "V14" smd circle
			(at -2.499995 1.499997 180)
			(size 0.508 0.508)
			(layers "F.Cu" "F.Mask" "F.Paste")
			(net "VDD_CORE")
		)
		(pad "V15" smd circle
			(at -1.499997 1.499997 180)
			(size 0.508 0.508)
			(layers "F.Cu" "F.Mask" "F.Paste")
			(net "GND")
		)
		(pad "V16" smd circle
			(at -0.499999 1.499997 180)
			(size 0.508 0.508)
			(layers "F.Cu" "F.Mask" "F.Paste")
			(net "VDD_CORE")
		)
		(pad "V17" smd circle
			(at 0.499999 1.499997 180)
			(size 0.508 0.508)
			(layers "F.Cu" "F.Mask" "F.Paste")
			(net "GND")
		)
		(pad "V18" smd circle
			(at 1.499997 1.499997 180)
			(size 0.508 0.508)
			(layers "F.Cu" "F.Mask" "F.Paste")
			(net "VDD_CORE")
		)
		(pad "V19" smd circle
			(at 2.499995 1.499997 180)
			(size 0.508 0.508)
			(layers "F.Cu" "F.Mask" "F.Paste")
			(net "GND")
		)
		(pad "V20" smd circle
			(at 3.499993 1.499997 180)
			(size 0.508 0.508)
			(layers "F.Cu" "F.Mask" "F.Paste")
			(net "VDD_CORE")
		)
		(pad "V21" smd circle
			(at 4.499991 1.499997 180)
			(size 0.508 0.508)
			(layers "F.Cu" "F.Mask" "F.Paste")
			(net "GND")
		)
		(pad "V22" smd circle
			(at 5.499989 1.499997 180)
			(size 0.508 0.508)
			(layers "F.Cu" "F.Mask" "F.Paste")
			(net "VDD_CORE")
		)
		(pad "V23" smd circle
			(at 6.500012 1.499997 180)
			(size 0.508 0.508)
			(layers "F.Cu" "F.Mask" "F.Paste")
			(net "GND")
		)
		(pad "V24" smd circle
			(at 7.50001 1.499997 180)
			(size 0.508 0.508)
			(layers "F.Cu" "F.Mask" "F.Paste")
			(net "VDD_CORE")
		)
		(pad "V25" smd circle
			(at 8.500008 1.499997 180)
			(size 0.508 0.508)
			(layers "F.Cu" "F.Mask" "F.Paste")
			(net "GND")
		)
		(pad "V26" smd circle
			(at 9.500006 1.499997 180)
			(size 0.508 0.508)
			(layers "F.Cu" "F.Mask" "F.Paste")
			(net "GND")
		)
		(pad "V27" smd circle
			(at 10.500004 1.499997 180)
			(size 0.508 0.508)
			(layers "F.Cu" "F.Mask" "F.Paste")
			(net "VDD_3.3V")
		)
		(pad "V28" smd circle
			(at 11.500002 1.499997 180)
			(size 0.508 0.508)
			(layers "F.Cu" "F.Mask" "F.Paste")
			(net "GND")
		)
		(pad "V29" smd circle
			(at 12.5 1.499997 180)
			(size 0.508 0.508)
			(layers "F.Cu" "F.Mask" "F.Paste")
			(net "GND")
		)
		(pad "V30" smd circle
			(at 13.499998 1.499997 180)
			(size 0.508 0.508)
			(layers "F.Cu" "F.Mask" "F.Paste")
			(net "NFP_CFG_SPI_FLASH_MISO")
		)
		(pad "V31" smd circle
			(at 14.499996 1.499997 180)
			(size 0.508 0.508)
			(layers "F.Cu" "F.Mask" "F.Paste")
			(net "NFP_SPI2_MISO")
		)
		(pad "V32" smd circle
			(at 15.499994 1.499997 180)
			(size 0.508 0.508)
			(layers "F.Cu" "F.Mask" "F.Paste")
			(net "_NC_SPIX_HOLD_L")
		)
		(pad "W1" smd circle
			(at -15.499994 2.499995 180)
			(size 0.508 0.508)
			(layers "F.Cu" "F.Mask" "F.Paste")
			(net "DDR0_32A_DQS3_P")
		)
		(pad "W2" smd circle
			(at -14.499996 2.499995 180)
			(size 0.508 0.508)
			(layers "F.Cu" "F.Mask" "F.Paste")
			(net "DDR0_32A_DQS3_N")
		)
		(pad "W3" smd circle
			(at -13.499998 2.499995 180)
			(size 0.508 0.508)
			(layers "F.Cu" "F.Mask" "F.Paste")
			(net "DDR0_32A_DQ29")
		)
		(pad "W4" smd circle
			(at -12.5 2.499995 180)
			(size 0.508 0.508)
			(layers "F.Cu" "F.Mask" "F.Paste")
			(net "DDR0_32A_DQ30")
		)
		(pad "W5" smd circle
			(at -11.500002 2.499995 180)
			(size 0.508 0.508)
			(layers "F.Cu" "F.Mask" "F.Paste")
			(net "DDR0_32A_DQ24")
		)
		(pad "W6" smd circle
			(at -10.500004 2.499995 180)
			(size 0.508 0.508)
			(layers "F.Cu" "F.Mask" "F.Paste")
			(net "DDR0_32A_DQ31")
		)
		(pad "W7" smd circle
			(at -9.500006 2.499995 180)
			(size 0.508 0.508)
			(layers "F.Cu" "F.Mask" "F.Paste")
			(net "_NC_DDR0_32A_A15")
		)
		(pad "W8" smd circle
			(at -8.500008 2.499995 180)
			(size 0.508 0.508)
			(layers "F.Cu" "F.Mask" "F.Paste")
			(net "_NC_DDR0_32A_CKE1")
		)
		(pad "W9" smd circle
			(at -7.50001 2.499995 180)
			(size 0.508 0.508)
			(layers "F.Cu" "F.Mask" "F.Paste")
			(net "DDR0_32A_CS0_L")
		)
		(pad "W10" smd circle
			(at -6.500012 2.499995 180)
			(size 0.508 0.508)
			(layers "F.Cu" "F.Mask" "F.Paste")
			(net "DDR0_32A_VREF")
		)
		(pad "W11" smd circle
			(at -5.499989 2.499995 180)
			(size 0.508 0.508)
			(layers "F.Cu" "F.Mask" "F.Paste")
			(net "VDD_CORE")
		)
		(pad "W12" smd circle
			(at -4.499991 2.499995 180)
			(size 0.508 0.508)
			(layers "F.Cu" "F.Mask" "F.Paste")
			(net "GND")
		)
		(pad "W13" smd circle
			(at -3.499993 2.499995 180)
			(size 0.508 0.508)
			(layers "F.Cu" "F.Mask" "F.Paste")
			(net "VDD_CORE")
		)
		(pad "W14" smd circle
			(at -2.499995 2.499995 180)
			(size 0.508 0.508)
			(layers "F.Cu" "F.Mask" "F.Paste")
			(net "GND")
		)
		(pad "W15" smd circle
			(at -1.499997 2.499995 180)
			(size 0.508 0.508)
			(layers "F.Cu" "F.Mask" "F.Paste")
			(net "VDD_CORE")
		)
		(pad "W16" smd circle
			(at -0.499999 2.499995 180)
			(size 0.508 0.508)
			(layers "F.Cu" "F.Mask" "F.Paste")
			(net "GND")
		)
		(pad "W17" smd circle
			(at 0.499999 2.499995 180)
			(size 0.508 0.508)
			(layers "F.Cu" "F.Mask" "F.Paste")
			(net "VDD_CORE")
		)
		(pad "W18" smd circle
			(at 1.499997 2.499995 180)
			(size 0.508 0.508)
			(layers "F.Cu" "F.Mask" "F.Paste")
			(net "GND")
		)
		(pad "W19" smd circle
			(at 2.499995 2.499995 180)
			(size 0.508 0.508)
			(layers "F.Cu" "F.Mask" "F.Paste")
			(net "VDD_CORE")
		)
		(pad "W20" smd circle
			(at 3.499993 2.499995 180)
			(size 0.508 0.508)
			(layers "F.Cu" "F.Mask" "F.Paste")
			(net "GND")
		)
		(pad "W21" smd circle
			(at 4.499991 2.499995 180)
			(size 0.508 0.508)
			(layers "F.Cu" "F.Mask" "F.Paste")
			(net "VDD_CORE")
		)
		(pad "W22" smd circle
			(at 5.499989 2.499995 180)
			(size 0.508 0.508)
			(layers "F.Cu" "F.Mask" "F.Paste")
			(net "GND")
		)
		(pad "W23" smd circle
			(at 6.500012 2.499995 180)
			(size 0.508 0.508)
			(layers "F.Cu" "F.Mask" "F.Paste")
			(net "VDD_CORE")
		)
		(pad "W24" smd circle
			(at 7.50001 2.499995 180)
			(size 0.508 0.508)
			(layers "F.Cu" "F.Mask" "F.Paste")
			(net "GND")
		)
		(pad "W25" smd circle
			(at 8.500008 2.499995 180)
			(size 0.508 0.508)
			(layers "F.Cu" "F.Mask" "F.Paste")
			(net "VDD_CORE")
		)
		(pad "W26" smd circle
			(at 9.500006 2.499995 180)
			(size 0.508 0.508)
			(layers "F.Cu" "F.Mask" "F.Paste")
			(net "VDD_3.3V")
		)
		(pad "W27" smd circle
			(at 10.500004 2.499995 180)
			(size 0.508 0.508)
			(layers "F.Cu" "F.Mask" "F.Paste")
			(net "GND")
		)
		(pad "W28" smd circle
			(at 11.500002 2.499995 180)
			(size 0.508 0.508)
			(layers "F.Cu" "F.Mask" "F.Paste")
			(net "MUX_NFP_GPIO1_NWK0_I2C_SDA")
		)
		(pad "W29" smd circle
			(at 12.5 2.499995 180)
			(size 0.508 0.508)
			(layers "F.Cu" "F.Mask" "F.Paste")
			(net "MUX_NFP_GPIO3_NWK1_I2C_SDA")
		)
		(pad "W30" smd circle
			(at 13.499998 2.499995 180)
			(size 0.508 0.508)
			(layers "F.Cu" "F.Mask" "F.Paste")
			(net "GND")
		)
		(pad "W31" smd circle
			(at 14.499996 2.499995 180)
			(size 0.508 0.508)
			(layers "F.Cu" "F.Mask" "F.Paste")
			(net "NFP_SPI2_CS")
		)
		(pad "W32" smd circle
			(at 15.499994 2.499995 180)
			(size 0.508 0.508)
			(layers "F.Cu" "F.Mask" "F.Paste")
			(net "_NC_NFP_SPIX_SEL1")
		)
		(pad "Y1" smd circle
			(at -15.499994 3.499993 180)
			(size 0.508 0.508)
			(layers "F.Cu" "F.Mask" "F.Paste")
			(net "DDR0_32A_DQ23")
		)
		(pad "Y2" smd circle
			(at -14.499996 3.499993 180)
			(size 0.508 0.508)
			(layers "F.Cu" "F.Mask" "F.Paste")
			(net "DDR0_32A_DQ22")
		)
		(pad "Y3" smd circle
			(at -13.499998 3.499993 180)
			(size 0.508 0.508)
			(layers "F.Cu" "F.Mask" "F.Paste")
			(net "DDR0_32A_DQS2_P")
		)
		(pad "Y4" smd circle
			(at -12.5 3.499993 180)
			(size 0.508 0.508)
			(layers "F.Cu" "F.Mask" "F.Paste")
			(net "DDR0_32A_DQS2_N")
		)
		(pad "Y5" smd circle
			(at -11.500002 3.499993 180)
			(size 0.508 0.508)
			(layers "F.Cu" "F.Mask" "F.Paste")
			(net "DDR0_32A_DM2")
		)
		(pad "Y6" smd circle
			(at -10.500004 3.499993 180)
			(size 0.508 0.508)
			(layers "F.Cu" "F.Mask" "F.Paste")
			(net "DDR0_32A_DQ20")
		)
		(pad "Y7" smd circle
			(at -9.500006 3.499993 180)
			(size 0.508 0.508)
			(layers "F.Cu" "F.Mask" "F.Paste")
			(net "DDR0_32A_A10")
		)
		(pad "Y8" smd circle
			(at -8.500008 3.499993 180)
			(size 0.508 0.508)
			(layers "F.Cu" "F.Mask" "F.Paste")
			(net "DDR0_32A_A12")
		)
		(pad "Y9" smd circle
			(at -7.50001 3.499993 180)
			(size 0.508 0.508)
			(layers "F.Cu" "F.Mask" "F.Paste")
			(net "_NC_DDR0_32A_ODT1")
		)
		(pad "Y10" smd circle
			(at -6.500012 3.499993 180)
			(size 0.508 0.508)
			(layers "F.Cu" "F.Mask" "F.Paste")
			(net "VDDA_DDR0_32B")
		)
		(pad "Y11" smd circle
			(at -5.499989 3.499993 180)
			(size 0.508 0.508)
			(layers "F.Cu" "F.Mask" "F.Paste")
			(net "GND")
		)
		(pad "Y12" smd circle
			(at -4.499991 3.499993 180)
			(size 0.508 0.508)
			(layers "F.Cu" "F.Mask" "F.Paste")
			(net "VDD_CORE")
		)
		(pad "Y13" smd circle
			(at -3.499993 3.499993 180)
			(size 0.508 0.508)
			(layers "F.Cu" "F.Mask" "F.Paste")
			(net "GND")
		)
		(pad "Y14" smd circle
			(at -2.499995 3.499993 180)
			(size 0.508 0.508)
			(layers "F.Cu" "F.Mask" "F.Paste")
			(net "VDD_CORE")
		)
		(pad "Y15" smd circle
			(at -1.499997 3.499993 180)
			(size 0.508 0.508)
			(layers "F.Cu" "F.Mask" "F.Paste")
			(net "GND")
		)
		(pad "Y16" smd circle
			(at -0.499999 3.499993 180)
			(size 0.508 0.508)
			(layers "F.Cu" "F.Mask" "F.Paste")
			(net "VDD_CORE")
		)
		(pad "Y17" smd circle
			(at 0.499999 3.499993 180)
			(size 0.508 0.508)
			(layers "F.Cu" "F.Mask" "F.Paste")
			(net "GND")
		)
		(pad "Y18" smd circle
			(at 1.499997 3.499993 180)
			(size 0.508 0.508)
			(layers "F.Cu" "F.Mask" "F.Paste")
			(net "VDD_CORE")
		)
		(pad "Y19" smd circle
			(at 2.499995 3.499993 180)
			(size 0.508 0.508)
			(layers "F.Cu" "F.Mask" "F.Paste")
			(net "GND")
		)
		(pad "Y20" smd circle
			(at 3.499993 3.499993 180)
			(size 0.508 0.508)
			(layers "F.Cu" "F.Mask" "F.Paste")
			(net "VDD_CORE")
		)
		(pad "Y21" smd circle
			(at 4.499991 3.499993 180)
			(size 0.508 0.508)
			(layers "F.Cu" "F.Mask" "F.Paste")
			(net "GND")
		)
		(pad "Y22" smd circle
			(at 5.499989 3.499993 180)
			(size 0.508 0.508)
			(layers "F.Cu" "F.Mask" "F.Paste")
			(net "VDD_CORE")
		)
		(pad "Y23" smd circle
			(at 6.500012 3.499993 180)
			(size 0.508 0.508)
			(layers "F.Cu" "F.Mask" "F.Paste")
			(net "_NC_VSS_SENSE")
		)
		(pad "Y24" smd circle
			(at 7.50001 3.499993 180)
			(size 0.508 0.508)
			(layers "F.Cu" "F.Mask" "F.Paste")
			(net "_NC_VDD_CORE3_SENSE")
		)
		(pad "Y25" smd circle
			(at 8.500008 3.499993 180)
			(size 0.508 0.508)
			(layers "F.Cu" "F.Mask" "F.Paste")
			(net "GND")
		)
		(pad "Y26" smd circle
			(at 9.500006 3.499993 180)
			(size 0.508 0.508)
			(layers "F.Cu" "F.Mask" "F.Paste")
			(net "VDD_3.3V")
		)
		(pad "Y27" smd circle
			(at 10.500004 3.499993 180)
			(size 0.508 0.508)
			(layers "F.Cu" "F.Mask" "F.Paste")
			(net "GND")
		)
		(pad "Y28" smd circle
			(at 11.500002 3.499993 180)
			(size 0.508 0.508)
			(layers "F.Cu" "F.Mask" "F.Paste")
			(net "MUX_NFP_GPIO0_NWK0_I2C_SCL")
		)
		(pad "Y29" smd circle
			(at 12.5 3.499993 180)
			(size 0.508 0.508)
			(layers "F.Cu" "F.Mask" "F.Paste")
			(net "MUX_NFP_GPIO2_NWK1_I2C_SCL")
		)
		(pad "Y30" smd circle
			(at 13.499998 3.499993 180)
			(size 0.508 0.508)
			(layers "F.Cu" "F.Mask" "F.Paste")
			(net "_NFP_JTAG_ARM_TDO")
		)
		(pad "Y31" smd circle
			(at 14.499996 3.499993 180)
			(size 0.508 0.508)
			(layers "F.Cu" "F.Mask" "F.Paste")
			(net "NFP_JTAG_ARM_TRST_L")
		)
		(pad "Y32" smd circle
			(at 15.499994 3.499993 180)
			(size 0.508 0.508)
			(layers "F.Cu" "F.Mask" "F.Paste")
			(net "NFP_JTAG_ARM_TDI")
		)
	)
)
